(kicad_pcb
	(version 20260206)
	(generator "pcbnew")
	(generator_version "10.0")
	(general
		(thickness 1.6)
		(legacy_teardrops no)
	)
	(paper "A4")
	(title_block
		(title "Bryce Canyon_F.DPB_16315-1-OCP.brd")
		(comment 1 "Bryce Canyon / footprint 2079 of 2223 (IO1), pads 197-202 of 202")
	)
	(layers
		(0 "F.Cu" signal "TOP")
		(4 "In1.Cu" signal "L2GND")
		(6 "In2.Cu" signal "L3")
		(8 "In3.Cu" signal "L4GND")
		(10 "In4.Cu" signal "L5")
		(12 "In5.Cu" signal "L6VCC")
		(14 "In6.Cu" signal "L7VCC")
		(16 "In7.Cu" signal "L8")
		(18 "In8.Cu" signal "L9GND")
		(20 "In9.Cu" signal "L10")
		(22 "In10.Cu" signal "L11GND")
		(2 "B.Cu" signal "BOTTOM")
		(9 "F.Adhes" user "F.Adhesive")
		(11 "B.Adhes" user "B.Adhesive")
		(13 "F.Paste" user "Package Geometry/Pastemask Top")
		(15 "B.Paste" user "Package Geometry/Pastemask Bottom")
		(5 "F.SilkS" user "Ref Des/Silkscreen Top")
		(7 "B.SilkS" user "Ref Des/Silkscreen Bottom")
		(1 "F.Mask" user "Board Geometry/Soldermask Top")
		(3 "B.Mask" user "Board Geometry/Soldermask Bottom")
		(17 "Dwgs.User" user "User.Drawings")
		(19 "Cmts.User" user "User.Comments")
		(21 "Eco1.User" user "User.Eco1")
		(23 "Eco2.User" user "User.Eco2")
		(25 "Edge.Cuts" user "Board Geometry/Outline")
		(27 "Margin" user)
		(31 "F.CrtYd" user "Package Geometry/Place Bound Top")
		(29 "B.CrtYd" user "Package Geometry/Place Bound Bottom")
		(35 "F.Fab" user "Ref Des/Assembly Top")
		(33 "B.Fab" user "Ref Des/Assembly Bottom")
	)
	(footprint ""
		(layer "B.Cu")
		(at 143.34998 -30.550104 180)
		(property "Reference" "IO1"
			(at 0 0 0)
			(layer "B.SilkS")
			(hide yes)
			(effects
				(font
					(size 1.27 1.27)
				)
				(justify mirror)
			)
		)
		(property "Value" "DM-AMP-CONN200-13R-6-GP-01"
			(at 47.5488 -16.5862 180)
			(unlocked yes)
			(layer "B.Fab")
			(hide yes)
			(effects
				(font
					(size 1.016 1.016)
					(thickness 0.1524)
				)
				(justify mirror)
			)
		)
		(property "Device Type" "DMFIT-200P-384346H577-01"
			(at 47.5488 -18.1102 180)
			(unlocked yes)
			(layer "B.Fab")
			(hide yes)
			(effects
				(font
					(size 1.016 1.016)
					(thickness 0.1524)
				)
				(justify mirror)
			)
		)
		(duplicate_pad_numbers_are_jumpers no)
		(pad "H11" thru_hole circle
			(at 25.200102 -12.199874)
			(size 0.664718 0.664718)
			(drill 0.359918)
			(layers "*.Cu" "*.Mask")
			(remove_unused_layers no)
			(net "PCIE_COMP_A_TO_IOM_A_18_DP")
			(clearance 0.264414)
			(padstack
				(mode custom)
				(layer "In1.Cu"
					(shape circle)
					(size 0.664718 0.664718)
					(clearance 0.264414)
				)
				(layer "In2.Cu"
					(shape circle)
					(size 0.664718 0.664718)
					(clearance 0.264414)
				)
				(layer "In3.Cu"
					(shape circle)
					(size 0.664718 0.664718)
					(clearance 0.264414)
				)
				(layer "In4.Cu"
					(shape circle)
					(size 0.664718 0.664718)
					(clearance 0.264414)
				)
				(layer "In5.Cu"
					(shape circle)
					(size 0.664718 0.664718)
					(clearance 0.264414)
				)
				(layer "In6.Cu"
					(shape circle)
					(size 0.762 0.762)
					(clearance 0.1651)
				)
				(layer "In7.Cu"
					(shape circle)
					(size 0.762 0.762)
					(clearance 0.1651)
				)
				(layer "In8.Cu"
					(shape circle)
					(size 0.762 0.762)
					(clearance 0.1651)
				)
				(layer "In9.Cu"
					(shape circle)
					(size 0.762 0.762)
					(clearance 0.1651)
				)
				(layer "In10.Cu"
					(shape circle)
					(size 0.762 0.762)
					(clearance 0.1651)
				)
				(layer "B.Cu"
					(shape circle)
					(size 0.762 0.762)
					(thermal_gap 0.1651)
					(clearance 0.1651)
				)
			)
		)
		(pad "H12" thru_hole circle
			(at 26.999946 -13.200126)
			(size 0.664718 0.664718)
			(drill 0.359918)
			(layers "*.Cu" "*.Mask")
			(remove_unused_layers no)
			(net "PCIE_COMP_A_TO_IOM_A_19_DP")
			(clearance 0.264414)
			(padstack
				(mode custom)
				(layer "In1.Cu"
					(shape circle)
					(size 0.664718 0.664718)
					(clearance 0.264414)
				)
				(layer "In2.Cu"
					(shape circle)
					(size 0.664718 0.664718)
					(clearance 0.264414)
				)
				(layer "In3.Cu"
					(shape circle)
					(size 0.664718 0.664718)
					(clearance 0.264414)
				)
				(layer "In4.Cu"
					(shape circle)
					(size 0.664718 0.664718)
					(clearance 0.264414)
				)
				(layer "In5.Cu"
					(shape circle)
					(size 0.664718 0.664718)
					(clearance 0.264414)
				)
				(layer "In6.Cu"
					(shape circle)
					(size 0.762 0.762)
					(clearance 0.1651)
				)
				(layer "In7.Cu"
					(shape circle)
					(size 0.762 0.762)
					(clearance 0.1651)
				)
				(layer "In8.Cu"
					(shape circle)
					(size 0.762 0.762)
					(clearance 0.1651)
				)
				(layer "In9.Cu"
					(shape circle)
					(size 0.762 0.762)
					(clearance 0.1651)
				)
				(layer "In10.Cu"
					(shape circle)
					(size 0.762 0.762)
					(clearance 0.1651)
				)
				(layer "B.Cu"
					(shape circle)
					(size 0.762 0.762)
					(thermal_gap 0.1651)
					(clearance 0.1651)
				)
			)
		)
		(pad "H13" thru_hole circle
			(at 28.800044 -12.199874)
			(size 0.664718 0.664718)
			(drill 0.359918)
			(layers "*.Cu" "*.Mask")
			(remove_unused_layers no)
			(net "PCIE_COMP_A_TO_IOM_A_20_DP")
			(clearance 0.264414)
			(padstack
				(mode custom)
				(layer "In1.Cu"
					(shape circle)
					(size 0.664718 0.664718)
					(clearance 0.264414)
				)
				(layer "In2.Cu"
					(shape circle)
					(size 0.664718 0.664718)
					(clearance 0.264414)
				)
				(layer "In3.Cu"
					(shape circle)
					(size 0.664718 0.664718)
					(clearance 0.264414)
				)
				(layer "In4.Cu"
					(shape circle)
					(size 0.664718 0.664718)
					(clearance 0.264414)
				)
				(layer "In5.Cu"
					(shape circle)
					(size 0.664718 0.664718)
					(clearance 0.264414)
				)
				(layer "In6.Cu"
					(shape circle)
					(size 0.762 0.762)
					(clearance 0.1651)
				)
				(layer "In7.Cu"
					(shape circle)
					(size 0.762 0.762)
					(clearance 0.1651)
				)
				(layer "In8.Cu"
					(shape circle)
					(size 0.762 0.762)
					(clearance 0.1651)
				)
				(layer "In9.Cu"
					(shape circle)
					(size 0.762 0.762)
					(clearance 0.1651)
				)
				(layer "In10.Cu"
					(shape circle)
					(size 0.762 0.762)
					(clearance 0.1651)
				)
				(layer "B.Cu"
					(shape circle)
					(size 0.762 0.762)
					(thermal_gap 0.1651)
					(clearance 0.1651)
				)
			)
		)
		(pad "H14" thru_hole circle
			(at 30.599888 -13.200126)
			(size 0.664718 0.664718)
			(drill 0.359918)
			(layers "*.Cu" "*.Mask")
			(remove_unused_layers no)
			(net "PCIE_COMP_A_TO_IOM_A_21_DP")
			(clearance 0.264414)
			(padstack
				(mode custom)
				(layer "In1.Cu"
					(shape circle)
					(size 0.664718 0.664718)
					(clearance 0.264414)
				)
				(layer "In2.Cu"
					(shape circle)
					(size 0.664718 0.664718)
					(clearance 0.264414)
				)
				(layer "In3.Cu"
					(shape circle)
					(size 0.664718 0.664718)
					(clearance 0.264414)
				)
				(layer "In4.Cu"
					(shape circle)
					(size 0.664718 0.664718)
					(clearance 0.264414)
				)
				(layer "In5.Cu"
					(shape circle)
					(size 0.664718 0.664718)
					(clearance 0.264414)
				)
				(layer "In6.Cu"
					(shape circle)
					(size 0.762 0.762)
					(clearance 0.1651)
				)
				(layer "In7.Cu"
					(shape circle)
					(size 0.762 0.762)
					(clearance 0.1651)
				)
				(layer "In8.Cu"
					(shape circle)
					(size 0.762 0.762)
					(clearance 0.1651)
				)
				(layer "In9.Cu"
					(shape circle)
					(size 0.762 0.762)
					(clearance 0.1651)
				)
				(layer "In10.Cu"
					(shape circle)
					(size 0.762 0.762)
					(clearance 0.1651)
				)
				(layer "B.Cu"
					(shape circle)
					(size 0.762 0.762)
					(thermal_gap 0.1651)
					(clearance 0.1651)
				)
			)
		)
		(pad "H15" thru_hole circle
			(at 32.399986 -12.199874)
			(size 0.664718 0.664718)
			(drill 0.359918)
			(layers "*.Cu" "*.Mask")
			(remove_unused_layers no)
			(net "PCIE_COMP_A_TO_IOM_A_22_DP")
			(clearance 0.264414)
			(padstack
				(mode custom)
				(layer "In1.Cu"
					(shape circle)
					(size 0.664718 0.664718)
					(clearance 0.264414)
				)
				(layer "In2.Cu"
					(shape circle)
					(size 0.664718 0.664718)
					(clearance 0.264414)
				)
				(layer "In3.Cu"
					(shape circle)
					(size 0.664718 0.664718)
					(clearance 0.264414)
				)
				(layer "In4.Cu"
					(shape circle)
					(size 0.664718 0.664718)
					(clearance 0.264414)
				)
				(layer "In5.Cu"
					(shape circle)
					(size 0.664718 0.664718)
					(clearance 0.264414)
				)
				(layer "In6.Cu"
					(shape circle)
					(size 0.762 0.762)
					(clearance 0.1651)
				)
				(layer "In7.Cu"
					(shape circle)
					(size 0.762 0.762)
					(clearance 0.1651)
				)
				(layer "In8.Cu"
					(shape circle)
					(size 0.762 0.762)
					(clearance 0.1651)
				)
				(layer "In9.Cu"
					(shape circle)
					(size 0.762 0.762)
					(clearance 0.1651)
				)
				(layer "In10.Cu"
					(shape circle)
					(size 0.762 0.762)
					(clearance 0.1651)
				)
				(layer "B.Cu"
					(shape circle)
					(size 0.762 0.762)
					(thermal_gap 0.1651)
					(clearance 0.1651)
				)
			)
		)
		(pad "H16" thru_hole circle
			(at 34.200084 -13.200126)
			(size 0.664718 0.664718)
			(drill 0.359918)
			(layers "*.Cu" "*.Mask")
			(remove_unused_layers no)
			(net "PCIE_COMP_A_TO_IOM_A_23_DP")
			(clearance 0.264414)
			(padstack
				(mode custom)
				(layer "In1.Cu"
					(shape circle)
					(size 0.664718 0.664718)
					(clearance 0.264414)
				)
				(layer "In2.Cu"
					(shape circle)
					(size 0.664718 0.664718)
					(clearance 0.264414)
				)
				(layer "In3.Cu"
					(shape circle)
					(size 0.664718 0.664718)
					(clearance 0.264414)
				)
				(layer "In4.Cu"
					(shape circle)
					(size 0.664718 0.664718)
					(clearance 0.264414)
				)
				(layer "In5.Cu"
					(shape circle)
					(size 0.664718 0.664718)
					(clearance 0.264414)
				)
				(layer "In6.Cu"
					(shape circle)
					(size 0.762 0.762)
					(clearance 0.1651)
				)
				(layer "In7.Cu"
					(shape circle)
					(size 0.762 0.762)
					(clearance 0.1651)
				)
				(layer "In8.Cu"
					(shape circle)
					(size 0.762 0.762)
					(clearance 0.1651)
				)
				(layer "In9.Cu"
					(shape circle)
					(size 0.762 0.762)
					(clearance 0.1651)
				)
				(layer "In10.Cu"
					(shape circle)
					(size 0.762 0.762)
					(clearance 0.1651)
				)
				(layer "B.Cu"
					(shape circle)
					(size 0.762 0.762)
					(thermal_gap 0.1651)
					(clearance 0.1651)
				)
			)
		)
	)
)
